(kicad_pcb
	(version 20260206)
	(generator "pcbnew")
	(generator_version "10.0")
	(general
		(thickness 1.6)
		(legacy_teardrops no)
	)
	(paper "A4")
	(title_block
		(title "04192023_DAF0TMB3IC0_F0TG_MB_C_brd_V02_OCP.brd")
		(comment 1 "Grand Teton / footprints 4553-4554 of 8354")
	)
	(layers
		(0 "F.Cu" signal "TOP")
		(4 "In1.Cu" signal "GND")
		(6 "In2.Cu" signal "IN1")
		(8 "In3.Cu" signal "GND1")
		(10 "In4.Cu" signal "IN2")
		(12 "In5.Cu" signal "GND2")
		(14 "In6.Cu" signal "IN3")
		(16 "In7.Cu" signal "GND3")
		(18 "In8.Cu" signal "VCC")
		(20 "In9.Cu" signal "VCC1")
		(22 "In10.Cu" signal "GND4")
		(24 "In11.Cu" signal "IN4")
		(26 "In12.Cu" signal "GND5")
		(28 "In13.Cu" signal "IN5")
		(30 "In14.Cu" signal "GND6")
		(32 "In15.Cu" signal "IN6")
		(34 "In16.Cu" signal "GND7")
		(2 "B.Cu" signal "BOTTOM")
		(9 "F.Adhes" user "F.Adhesive")
		(11 "B.Adhes" user "B.Adhesive")
		(13 "F.Paste" user "Package Geometry/Pastemask Top")
		(15 "B.Paste" user "Package Geometry/Pastemask Bottom")
		(5 "F.SilkS" user "Ref Des/Silkscreen Top")
		(7 "B.SilkS" user "Ref Des/Silkscreen Bottom")
		(1 "F.Mask" user "Board Geometry/Soldermask Top")
		(3 "B.Mask" user "Board Geometry/Soldermask Bottom")
		(17 "Dwgs.User" user "User.Drawings")
		(19 "Cmts.User" user "User.Comments")
		(21 "Eco1.User" user "User.Eco1")
		(23 "Eco2.User" user "User.Eco2")
		(25 "Edge.Cuts" user "Board Geometry/Outline")
		(27 "Margin" user)
		(31 "F.CrtYd" user "Package Geometry/Place Bound Top")
		(29 "B.CrtYd" user "Package Geometry/Place Bound Bottom")
		(35 "F.Fab" user "Ref Des/Assembly Top")
		(33 "B.Fab" user "Ref Des/Assembly Bottom")
	)
	(footprint ""
		(layer "F.Cu")
		(at 277.352252 -124.368814)
		(property "Reference" "R318"
			(at 0 0 0)
			(layer "F.SilkS")
			(hide yes)
			(effects
				(font
					(size 1.27 1.27)
				)
			)
		)
		(property "Value" ""
			(at 0 0 0)
			(layer "F.Fab")
			(effects
				(font
					(size 1.27 1.27)
				)
			)
		)
		(duplicate_pad_numbers_are_jumpers no)
		(fp_line
			(start -0.7874 -0.4064)
			(end 0.7874 -0.4064)
			(stroke
				(width 0.1524)
				(type default)
			)
			(layer "F.SilkS")
		)
		(fp_line
			(start -0.7874 0.4064)
			(end -0.7874 -0.4064)
			(stroke
				(width 0.1524)
				(type default)
			)
			(layer "F.SilkS")
		)
		(fp_line
			(start 0.7874 -0.4064)
			(end 0.7874 0.4064)
			(stroke
				(width 0.1524)
				(type default)
			)
			(layer "F.SilkS")
		)
		(fp_line
			(start 0.7874 0.4064)
			(end -0.7874 0.4064)
			(stroke
				(width 0.1524)
				(type default)
			)
			(layer "F.SilkS")
		)
		(fp_line
			(start -0.67945 -0.305054)
			(end -0.12065 -0.305054)
			(stroke
				(width 0.1)
				(type default)
			)
			(layer "F.Fab")
		)
		(fp_line
			(start -0.67945 0.3048)
			(end -0.67945 -0.305054)
			(stroke
				(width 0.1)
				(type default)
			)
			(layer "F.Fab")
		)
		(fp_line
			(start -0.12065 -0.305054)
			(end -0.12065 -0.2794)
			(stroke
				(width 0.1)
				(type default)
			)
			(layer "F.Fab")
		)
		(fp_line
			(start -0.12065 -0.2794)
			(end 0.12065 -0.2794)
			(stroke
				(width 0.1)
				(type default)
			)
			(layer "F.Fab")
		)
		(fp_line
			(start -0.12065 0.2794)
			(end -0.12065 0.3048)
			(stroke
				(width 0.1)
				(type default)
			)
			(layer "F.Fab")
		)
		(fp_line
			(start -0.12065 0.3048)
			(end -0.67945 0.3048)
			(stroke
				(width 0.1)
				(type default)
			)
			(layer "F.Fab")
		)
		(fp_line
			(start 0.120396 0.2794)
			(end -0.12065 0.2794)
			(stroke
				(width 0.1)
				(type default)
			)
			(layer "F.Fab")
		)
		(fp_line
			(start 0.120396 0.3048)
			(end 0.120396 0.2794)
			(stroke
				(width 0.1)
				(type default)
			)
			(layer "F.Fab")
		)
		(fp_line
			(start 0.12065 -0.3048)
			(end 0.67945 -0.3048)
			(stroke
				(width 0.1)
				(type default)
			)
			(layer "F.Fab")
		)
		(fp_line
			(start 0.12065 -0.2794)
			(end 0.12065 -0.3048)
			(stroke
				(width 0.1)
				(type default)
			)
			(layer "F.Fab")
		)
		(fp_line
			(start 0.67945 -0.3048)
			(end 0.67945 0.3048)
			(stroke
				(width 0.1)
				(type default)
			)
			(layer "F.Fab")
		)
		(fp_line
			(start 0.67945 0.3048)
			(end 0.120396 0.3048)
			(stroke
				(width 0.1)
				(type default)
			)
			(layer "F.Fab")
		)
		(pad "1" smd circle
			(at -0.40005 0)
			(size 0 0)
			(layers "F.Cu" "F.Mask" "F.Paste")
			(net "P3V3_AUX")
		)
		(pad "2" smd circle
			(at 0.40005 0)
			(size 0 0)
			(layers "F.Cu" "F.Mask" "F.Paste")
			(net "PCA9548_PCIE3_ADDR1")
		)
	)
	(footprint ""
		(layer "F.Cu")
		(at 387.206998 -162.65271 180)
		(property "Reference" "PC596"
			(at 1.796796 -2.887472 0)
			(unlocked yes)
			(layer "F.SilkS")
			(effects
				(font
					(size 0.7874 0.5842)
					(thickness 0.1524)
				)
				(justify left)
			)
		)
		(property "Value" ""
			(at 0 0 180)
			(layer "F.Fab")
			(effects
				(font
					(size 1.27 1.27)
				)
			)
		)
		(duplicate_pad_numbers_are_jumpers no)
		(fp_line
			(start -3.400044 1.249934)
			(end 3.400044 1.249934)
			(stroke
				(width 0.1524)
				(type default)
			)
			(layer "F.SilkS")
		)
		(fp_circle
			(center 0 1.249934)
			(end -3.400044 1.249934)
			(stroke
				(width 0.1524)
				(type default)
			)
			(fill no)
			(layer "F.SilkS")
		)
		(fp_poly
			(pts
				(arc
					(start 3.400044 1.249934)
					(mid 0 4.649978)
					(end -3.400044 1.249934)
				)
			)
			(stroke
				(width 0)
				(type default)
			)
			(fill yes)
			(layer "F.SilkS")
		)
		(fp_circle
			(center 0 1.249934)
			(end -3.400044 1.249934)
			(stroke
				(width 0.1)
				(type default)
			)
			(fill no)
			(layer "F.Fab")
		)
		(pad "1" thru_hole rect
			(at 0 0 180)
			(size 1.524 1.524)
			(drill 1.016)
			(layers "*.Cu" "*.Mask")
			(remove_unused_layers no)
			(net "SW_P12V_AUX_PVDDCR_SOC_P0_FLT")
			(clearance 0)
			(padstack
				(mode front_inner_back)
				(layer "Inner"
					(shape circle)
					(size 1.524 1.524)
					(clearance 0)
				)
				(layer "B.Cu"
					(shape rect)
					(size 1.524 1.524)
					(clearance 0)
				)
			)
		)
		(pad "2" thru_hole circle
			(at 0 2.500122 180)
			(size 1.524 1.524)
			(drill 1.016)
			(layers "*.Cu" "*.Mask")
			(remove_unused_layers no)
			(net "GND")
			(clearance 0)
		)
	)
)
